# S9S_MB_2U (Grand Teton) — schematic netlist excerpt (pin names and nets, part order shuffled) for the footprints in the layout excerpt that follows; sources: Cadence DE-HDL packaged netlist, KiCad conversion of 03242023_DA0F0TMBIJ0_F0T_Motherboard_J_brd_V01_OCP.brd

R4560  Q_RES  4.7K 5% CHIP  pkg 0402LF  page 146 : A = P3V3_AUX ; B = SWB_HSC_PWRGD_N
R539  Q_RES  1K 1% CHIP  pkg 0402LF  page 231 : A = PCA9548_PCIE3_ADDR1 ; B = GND

(kicad_pcb
	(version 20260206)
	(generator "pcbnew")
	(generator_version "10.0")
	(general
		(thickness 1.6)
		(legacy_teardrops no)
	)
	(paper "A4")
	(title_block
		(title "03242023_DA0F0TMBIJ0_F0T_Motherboard_J_brd_V01_OCP.brd")
		(comment 1 "Grand Teton / footprints 3920-3921 of 6105")
	)
	(layers
		(0 "F.Cu" signal "TOP")
		(4 "In1.Cu" signal "GND")
		(6 "In2.Cu" signal "IN1")
		(8 "In3.Cu" signal "GND1")
		(10 "In4.Cu" signal "IN2")
		(12 "In5.Cu" signal "GND2")
		(14 "In6.Cu" signal "IN3")
		(16 "In7.Cu" signal "GND3")
		(18 "In8.Cu" signal "VCC")
		(20 "In9.Cu" signal "VCC1")
		(22 "In10.Cu" signal "GND4")
		(24 "In11.Cu" signal "IN4")
		(26 "In12.Cu" signal "GND5")
		(28 "In13.Cu" signal "IN5")
		(30 "In14.Cu" signal "GND6")
		(32 "In15.Cu" signal "IN6")
		(34 "In16.Cu" signal "GND7")
		(2 "B.Cu" signal "BOTTOM")
		(9 "F.Adhes" user "F.Adhesive")
		(11 "B.Adhes" user "B.Adhesive")
		(13 "F.Paste" user "Package Geometry/Pastemask Top")
		(15 "B.Paste" user "Package Geometry/Pastemask Bottom")
		(5 "F.SilkS" user "Ref Des/Silkscreen Top")
		(7 "B.SilkS" user "Ref Des/Silkscreen Bottom")
		(1 "F.Mask" user "Board Geometry/Soldermask Top")
		(3 "B.Mask" user "Board Geometry/Soldermask Bottom")
		(17 "Dwgs.User" user "User.Drawings")
		(19 "Cmts.User" user "User.Comments")
		(21 "Eco1.User" user "User.Eco1")
		(23 "Eco2.User" user "User.Eco2")
		(25 "Edge.Cuts" user "Board Geometry/Outline")
		(27 "Margin" user)
		(31 "F.CrtYd" user "Package Geometry/Place Bound Top")
		(29 "B.CrtYd" user "Package Geometry/Place Bound Bottom")
		(35 "F.Fab" user "Ref Des/Assembly Top")
		(33 "B.Fab" user "Ref Des/Assembly Bottom")
	)
	(footprint ""
		(layer "F.Cu")
		(at 113.494312 -137.799826 180)
		(property "Reference" "R539"
			(at 0 0 180)
			(layer "F.SilkS")
			(hide yes)
			(effects
				(font
					(size 1.27 1.27)
				)
			)
		)
		(property "Value" ""
			(at 0 0 180)
			(layer "F.Fab")
			(effects
				(font
					(size 1.27 1.27)
				)
			)
		)
		(duplicate_pad_numbers_are_jumpers no)
		(fp_line
			(start 0.7874 0.4064)
			(end -0.7874 0.4064)
			(stroke
				(width 0.1524)
				(type default)
			)
			(layer "F.SilkS")
		)
		(fp_line
			(start 0.7874 -0.4064)
			(end 0.7874 0.4064)
			(stroke
				(width 0.1524)
				(type default)
			)
			(layer "F.SilkS")
		)
		(fp_line
			(start -0.7874 0.4064)
			(end -0.7874 -0.4064)
			(stroke
				(width 0.1524)
				(type default)
			)
			(layer "F.SilkS")
		)
		(fp_line
			(start -0.7874 -0.4064)
			(end 0.7874 -0.4064)
			(stroke
				(width 0.1524)
				(type default)
			)
			(layer "F.SilkS")
		)
		(fp_line
			(start 0.67945 0.3048)
			(end 0.120396 0.3048)
			(stroke
				(width 0.1)
				(type default)
			)
			(layer "F.Fab")
		)
		(fp_line
			(start 0.67945 -0.3048)
			(end 0.67945 0.3048)
			(stroke
				(width 0.1)
				(type default)
			)
			(layer "F.Fab")
		)
		(fp_line
			(start 0.12065 -0.2794)
			(end 0.12065 -0.3048)
			(stroke
				(width 0.1)
				(type default)
			)
			(layer "F.Fab")
		)
		(fp_line
			(start 0.12065 -0.3048)
			(end 0.67945 -0.3048)
			(stroke
				(width 0.1)
				(type default)
			)
			(layer "F.Fab")
		)
		(fp_line
			(start 0.120396 0.3048)
			(end 0.120396 0.2794)
			(stroke
				(width 0.1)
				(type default)
			)
			(layer "F.Fab")
		)
		(fp_line
			(start 0.120396 0.2794)
			(end -0.12065 0.2794)
			(stroke
				(width 0.1)
				(type default)
			)
			(layer "F.Fab")
		)
		(fp_line
			(start -0.12065 0.3048)
			(end -0.67945 0.3048)
			(stroke
				(width 0.1)
				(type default)
			)
			(layer "F.Fab")
		)
		(fp_line
			(start -0.12065 0.2794)
			(end -0.12065 0.3048)
			(stroke
				(width 0.1)
				(type default)
			)
			(layer "F.Fab")
		)
		(fp_line
			(start -0.12065 -0.2794)
			(end 0.12065 -0.2794)
			(stroke
				(width 0.1)
				(type default)
			)
			(layer "F.Fab")
		)
		(fp_line
			(start -0.12065 -0.305054)
			(end -0.12065 -0.2794)
			(stroke
				(width 0.1)
				(type default)
			)
			(layer "F.Fab")
		)
		(fp_line
			(start -0.67945 0.3048)
			(end -0.67945 -0.305054)
			(stroke
				(width 0.1)
				(type default)
			)
			(layer "F.Fab")
		)
		(fp_line
			(start -0.67945 -0.305054)
			(end -0.12065 -0.305054)
			(stroke
				(width 0.1)
				(type default)
			)
			(layer "F.Fab")
		)
		(pad "1" smd circle
			(at -0.40005 0 180)
			(size 0 0)
			(layers "F.Cu" "F.Mask" "F.Paste")
			(net "PCA9548_PCIE3_ADDR1")
		)
		(pad "2" smd circle
			(at 0.40005 0 180)
			(size 0 0)
			(layers "F.Cu" "F.Mask" "F.Paste")
			(net "GND")
		)
	)
	(footprint ""
		(layer "F.Cu")
		(at 363.22 -415.889948 180)
		(property "Reference" "R4560"
			(at 0 0 180)
			(layer "F.SilkS")
			(hide yes)
			(effects
				(font
					(size 1.27 1.27)
				)
			)
		)
		(property "Value" ""
			(at 0 0 180)
			(layer "F.Fab")
			(effects
				(font
					(size 1.27 1.27)
				)
			)
		)
		(duplicate_pad_numbers_are_jumpers no)
		(fp_line
			(start 0.7874 0.4064)
			(end -0.7874 0.4064)
			(stroke
				(width 0.1524)
				(type default)
			)
			(layer "F.SilkS")
		)
		(fp_line
			(start 0.7874 -0.4064)
			(end 0.7874 0.4064)
			(stroke
				(width 0.1524)
				(type default)
			)
			(layer "F.SilkS")
		)
		(fp_line
			(start -0.7874 0.4064)
			(end -0.7874 -0.4064)
			(stroke
				(width 0.1524)
				(type default)
			)
			(layer "F.SilkS")
		)
		(fp_line
			(start -0.7874 -0.4064)
			(end 0.7874 -0.4064)
			(stroke
				(width 0.1524)
				(type default)
			)
			(layer "F.SilkS")
		)
		(fp_line
			(start 0.67945 0.3048)
			(end 0.120396 0.3048)
			(stroke
				(width 0.1)
				(type default)
			)
			(layer "F.Fab")
		)
		(fp_line
			(start 0.67945 -0.3048)
			(end 0.67945 0.3048)
			(stroke
				(width 0.1)
				(type default)
			)
			(layer "F.Fab")
		)
		(fp_line
			(start 0.12065 -0.2794)
			(end 0.12065 -0.3048)
			(stroke
				(width 0.1)
				(type default)
			)
			(layer "F.Fab")
		)
		(fp_line
			(start 0.12065 -0.3048)
			(end 0.67945 -0.3048)
			(stroke
				(width 0.1)
				(type default)
			)
			(layer "F.Fab")
		)
		(fp_line
			(start 0.120396 0.3048)
			(end 0.120396 0.2794)
			(stroke
				(width 0.1)
				(type default)
			)
			(layer "F.Fab")
		)
		(fp_line
			(start 0.120396 0.2794)
			(end -0.12065 0.2794)
			(stroke
				(width 0.1)
				(type default)
			)
			(layer "F.Fab")
		)
		(fp_line
			(start -0.12065 0.3048)
			(end -0.67945 0.3048)
			(stroke
				(width 0.1)
				(type default)
			)
			(layer "F.Fab")
		)
		(fp_line
			(start -0.12065 0.2794)
			(end -0.12065 0.3048)
			(stroke
				(width 0.1)
				(type default)
			)
			(layer "F.Fab")
		)
		(fp_line
			(start -0.12065 -0.2794)
			(end 0.12065 -0.2794)
			(stroke
				(width 0.1)
				(type default)
			)
			(layer "F.Fab")
		)
		(fp_line
			(start -0.12065 -0.305054)
			(end -0.12065 -0.2794)
			(stroke
				(width 0.1)
				(type default)
			)
			(layer "F.Fab")
		)
		(fp_line
			(start -0.67945 0.3048)
			(end -0.67945 -0.305054)
			(stroke
				(width 0.1)
				(type default)
			)
			(layer "F.Fab")
		)
		(fp_line
			(start -0.67945 -0.305054)
			(end -0.12065 -0.305054)
			(stroke
				(width 0.1)
				(type default)
			)
			(layer "F.Fab")
		)
		(pad "1" smd circle
			(at -0.40005 0 180)
			(size 0 0)
			(layers "F.Cu" "F.Mask" "F.Paste")
			(net "P3V3_AUX")
		)
		(pad "2" smd circle
			(at 0.40005 0 180)
			(size 0 0)
			(layers "F.Cu" "F.Mask" "F.Paste")
			(net "SWB_HSC_PWRGD_N")
		)
	)
)
